(kicad_pcb
	(version 20260206)
	(generator "pcbnew")
	(generator_version "10.0")
	(general
		(thickness 1.6)
		(legacy_teardrops no)
	)
	(paper "A4")
	(title_block
		(title "Bryce Canyon_IOM_M2_16342-2_OCP.brd")
		(comment 1 "Bryce Canyon / footprints 655-662 of 1146")
	)
	(layers
		(0 "F.Cu" signal "TOP")
		(4 "In1.Cu" signal "L2GND")
		(6 "In2.Cu" signal "L3")
		(8 "In3.Cu" signal "L4VCC")
		(10 "In4.Cu" signal "L5VCC")
		(12 "In5.Cu" signal "L6")
		(14 "In6.Cu" signal "L7GND")
		(2 "B.Cu" signal "BOTTOM")
		(9 "F.Adhes" user "F.Adhesive")
		(11 "B.Adhes" user "B.Adhesive")
		(13 "F.Paste" user "Package Geometry/Pastemask Top")
		(15 "B.Paste" user "Package Geometry/Pastemask Bottom")
		(5 "F.SilkS" user "Ref Des/Silkscreen Top")
		(7 "B.SilkS" user "Ref Des/Silkscreen Bottom")
		(1 "F.Mask" user "Board Geometry/Soldermask Top")
		(3 "B.Mask" user "Board Geometry/Soldermask Bottom")
		(17 "Dwgs.User" user "User.Drawings")
		(19 "Cmts.User" user "User.Comments")
		(21 "Eco1.User" user "User.Eco1")
		(23 "Eco2.User" user "User.Eco2")
		(25 "Edge.Cuts" user "Board Geometry/Outline")
		(27 "Margin" user)
		(31 "F.CrtYd" user "Package Geometry/Place Bound Top")
		(29 "B.CrtYd" user "Package Geometry/Place Bound Bottom")
		(35 "F.Fab" user "Ref Des/Assembly Top")
		(33 "B.Fab" user "Ref Des/Assembly Bottom")
	)
	(footprint ""
		(layer "F.Cu")
		(at 45.913802 -119.34952 -90)
		(property "Reference" "R83"
			(at 0 0 270)
			(layer "F.SilkS")
			(hide yes)
			(effects
				(font
					(size 1.27 1.27)
				)
			)
		)
		(property "Value" "2K2R2J-2-GP"
			(at 0.064008 -3.993896 270)
			(unlocked yes)
			(layer "F.Fab")
			(hide yes)
			(effects
				(font
					(size 1.016 1.016)
					(thickness 0.1524)
				)
			)
		)
		(property "Device Type" "R402H16"
			(at 0.064008 -5.517896 270)
			(unlocked yes)
			(layer "F.Fab")
			(hide yes)
			(effects
				(font
					(size 1.016 1.016)
					(thickness 0.1524)
				)
			)
		)
		(duplicate_pad_numbers_are_jumpers no)
		(fp_line
			(start -0.508 -0.9398)
			(end -0.508 0.9398)
			(stroke
				(width 0.1524)
				(type default)
			)
			(layer "F.SilkS")
		)
		(fp_line
			(start 0.508 -0.9398)
			(end -0.508 -0.9398)
			(stroke
				(width 0.1524)
				(type default)
			)
			(layer "F.SilkS")
		)
		(fp_rect
			(start -0.508 0.9398)
			(end 0.508 -0.9398)
			(stroke
				(width 0)
				(type default)
			)
			(fill no)
			(layer "F.CrtYd")
		)
		(fp_rect
			(start -0.508 0.9398)
			(end 0.508 -0.9398)
			(stroke
				(width 0)
				(type default)
			)
			(fill no)
			(layer "F.Fab")
		)
		(pad "1" smd custom
			(at 0 -0.4445 270)
			(size 0.1397 0.1397)
			(layers "F.Cu" "F.Mask" "F.Paste")
			(net "P3V3_STBY")
			(options
				(clearance outline)
				(anchor circle)
			)
			(primitives
				(gr_poly
					(pts
						(arc
							(start -0.1778 -0.2794)
							(mid -0.249642 -0.249642)
							(end -0.2794 -0.1778)
						)
						(arc
							(start -0.2794 0.1778)
							(mid -0.249642 0.249642)
							(end -0.1778 0.2794)
						)
						(arc
							(start 0.1778 0.2794)
							(mid 0.249642 0.249642)
							(end 0.2794 0.1778)
						)
						(arc
							(start 0.2794 -0.1778)
							(mid 0.249642 -0.249642)
							(end 0.1778 -0.2794)
						)
					)
					(width 0)
					(fill yes)
				)
			)
		)
		(pad "2" smd custom
			(at 0 0.4445 270)
			(size 0.1397 0.1397)
			(layers "F.Cu" "F.Mask" "F.Paste")
			(net "FLA0_SPI_RST")
			(options
				(clearance outline)
				(anchor circle)
			)
			(primitives
				(gr_poly
					(pts
						(arc
							(start -0.1778 -0.2794)
							(mid -0.249642 -0.249642)
							(end -0.2794 -0.1778)
						)
						(arc
							(start -0.2794 0.1778)
							(mid -0.249642 0.249642)
							(end -0.1778 0.2794)
						)
						(arc
							(start 0.1778 0.2794)
							(mid 0.249642 0.249642)
							(end 0.2794 0.1778)
						)
						(arc
							(start 0.2794 -0.1778)
							(mid 0.249642 -0.249642)
							(end 0.1778 -0.2794)
						)
					)
					(width 0)
					(fill yes)
				)
			)
		)
	)
	(footprint ""
		(layer "F.Cu")
		(at 61.2394 -138.2014)
		(property "Reference" "TP77"
			(at 0 0 0)
			(layer "F.SilkS")
			(hide yes)
			(effects
				(font
					(size 1.27 1.27)
				)
			)
		)
		(property "Value" "TPAD28-2-GP"
			(at -0.0127 -1.6637 0)
			(unlocked yes)
			(layer "F.Fab")
			(hide yes)
			(effects
				(font
					(size 1.016 1.016)
					(thickness 0.1524)
				)
			)
		)
		(property "Device Type" "TPAD28"
			(at -0.0127 -3.1877 0)
			(unlocked yes)
			(layer "F.Fab")
			(hide yes)
			(effects
				(font
					(size 1.016 1.016)
					(thickness 0.1524)
				)
			)
		)
		(duplicate_pad_numbers_are_jumpers no)
		(fp_poly
			(pts
				(arc
					(start 0.3556 0)
					(mid -0.3556 0)
					(end 0.3556 0)
				)
			)
			(stroke
				(width 0)
				(type default)
			)
			(fill no)
			(layer "F.CrtYd")
		)
		(fp_poly
			(pts
				(arc
					(start 0.6096 0)
					(mid -0.6096 0)
					(end 0.6096 0)
				)
			)
			(stroke
				(width 0)
				(type default)
			)
			(fill no)
			(layer "F.Fab")
		)
		(pad "1" smd circle
			(at 0 0)
			(size 0.7112 0.7112)
			(layers "F.Cu" "F.Mask" "F.Paste")
			(net "TP_BMC_GPIOI7")
		)
	)
	(footprint ""
		(layer "F.Cu")
		(at 55.245 -130.064764 -90)
		(property "Reference" "R146"
			(at 0 0 270)
			(layer "F.SilkS")
			(hide yes)
			(effects
				(font
					(size 1.27 1.27)
				)
			)
		)
		(property "Value" "100KR2F-L1-GP"
			(at 0.064008 -3.993896 270)
			(unlocked yes)
			(layer "F.Fab")
			(hide yes)
			(effects
				(font
					(size 1.016 1.016)
					(thickness 0.1524)
				)
			)
		)
		(property "Device Type" "R402H16"
			(at 0.064008 -5.517896 270)
			(unlocked yes)
			(layer "F.Fab")
			(hide yes)
			(effects
				(font
					(size 1.016 1.016)
					(thickness 0.1524)
				)
			)
		)
		(duplicate_pad_numbers_are_jumpers no)
		(fp_line
			(start -0.508 -0.9398)
			(end -0.508 0.9398)
			(stroke
				(width 0.1524)
				(type default)
			)
			(layer "F.SilkS")
		)
		(fp_line
			(start 0.508 -0.9398)
			(end -0.508 -0.9398)
			(stroke
				(width 0.1524)
				(type default)
			)
			(layer "F.SilkS")
		)
		(fp_rect
			(start -0.508 0.9398)
			(end 0.508 -0.9398)
			(stroke
				(width 0)
				(type default)
			)
			(fill no)
			(layer "F.CrtYd")
		)
		(fp_rect
			(start -0.508 0.9398)
			(end 0.508 -0.9398)
			(stroke
				(width 0)
				(type default)
			)
			(fill no)
			(layer "F.Fab")
		)
		(pad "1" smd custom
			(at 0 -0.4445 270)
			(size 0.1397 0.1397)
			(layers "F.Cu" "F.Mask" "F.Paste")
			(net "LPC_CPU_CLKOUT0")
			(options
				(clearance outline)
				(anchor circle)
			)
			(primitives
				(gr_poly
					(pts
						(arc
							(start -0.1778 -0.2794)
							(mid -0.249642 -0.249642)
							(end -0.2794 -0.1778)
						)
						(arc
							(start -0.2794 0.1778)
							(mid -0.249642 0.249642)
							(end -0.1778 0.2794)
						)
						(arc
							(start 0.1778 0.2794)
							(mid 0.249642 0.249642)
							(end 0.2794 0.1778)
						)
						(arc
							(start 0.2794 -0.1778)
							(mid 0.249642 -0.249642)
							(end 0.1778 -0.2794)
						)
					)
					(width 0)
					(fill yes)
				)
			)
		)
		(pad "2" smd custom
			(at 0 0.4445 270)
			(size 0.1397 0.1397)
			(layers "F.Cu" "F.Mask" "F.Paste")
			(net "GND")
			(options
				(clearance outline)
				(anchor circle)
			)
			(primitives
				(gr_poly
					(pts
						(arc
							(start -0.1778 -0.2794)
							(mid -0.249642 -0.249642)
							(end -0.2794 -0.1778)
						)
						(arc
							(start -0.2794 0.1778)
							(mid -0.249642 0.249642)
							(end -0.1778 0.2794)
						)
						(arc
							(start 0.1778 0.2794)
							(mid 0.249642 0.249642)
							(end 0.2794 0.1778)
						)
						(arc
							(start 0.2794 -0.1778)
							(mid 0.249642 -0.249642)
							(end 0.1778 -0.2794)
						)
					)
					(width 0)
					(fill yes)
				)
			)
		)
	)
	(footprint ""
		(layer "F.Cu")
		(at 46.348396 -131.823714 180)
		(property "Reference" "R264"
			(at 0 0 180)
			(layer "F.SilkS")
			(hide yes)
			(effects
				(font
					(size 1.27 1.27)
				)
			)
		)
		(property "Value" "4K7R2F-GP"
			(at 0.064008 -3.993896 180)
			(unlocked yes)
			(layer "F.Fab")
			(hide yes)
			(effects
				(font
					(size 1.016 1.016)
					(thickness 0.1524)
				)
			)
		)
		(property "Device Type" "R402H16"
			(at 0.064008 -5.517896 180)
			(unlocked yes)
			(layer "F.Fab")
			(hide yes)
			(effects
				(font
					(size 1.016 1.016)
					(thickness 0.1524)
				)
			)
		)
		(duplicate_pad_numbers_are_jumpers no)
		(fp_line
			(start 0.508 -0.9398)
			(end -0.508 -0.9398)
			(stroke
				(width 0.1524)
				(type default)
			)
			(layer "F.SilkS")
		)
		(fp_line
			(start -0.508 -0.9398)
			(end -0.508 0.9398)
			(stroke
				(width 0.1524)
				(type default)
			)
			(layer "F.SilkS")
		)
		(fp_rect
			(start -0.508 0.9398)
			(end 0.508 -0.9398)
			(stroke
				(width 0)
				(type default)
			)
			(fill no)
			(layer "F.CrtYd")
		)
		(fp_rect
			(start -0.508 0.9398)
			(end 0.508 -0.9398)
			(stroke
				(width 0)
				(type default)
			)
			(fill no)
			(layer "F.Fab")
		)
		(pad "1" smd custom
			(at 0 -0.4445 180)
			(size 0.1397 0.1397)
			(layers "F.Cu" "F.Mask" "F.Paste")
			(net "P3V3_STBY")
			(options
				(clearance outline)
				(anchor circle)
			)
			(primitives
				(gr_poly
					(pts
						(arc
							(start -0.1778 -0.2794)
							(mid -0.249642 -0.249642)
							(end -0.2794 -0.1778)
						)
						(arc
							(start -0.2794 0.1778)
							(mid -0.249642 0.249642)
							(end -0.1778 0.2794)
						)
						(arc
							(start 0.1778 0.2794)
							(mid 0.249642 0.249642)
							(end 0.2794 0.1778)
						)
						(arc
							(start 0.2794 -0.1778)
							(mid 0.249642 -0.249642)
							(end 0.1778 -0.2794)
						)
					)
					(width 0)
					(fill yes)
				)
			)
		)
		(pad "2" smd custom
			(at 0 0.4445 180)
			(size 0.1397 0.1397)
			(layers "F.Cu" "F.Mask" "F.Paste")
			(net "BMC_GPIOY2")
			(options
				(clearance outline)
				(anchor circle)
			)
			(primitives
				(gr_poly
					(pts
						(arc
							(start -0.1778 -0.2794)
							(mid -0.249642 -0.249642)
							(end -0.2794 -0.1778)
						)
						(arc
							(start -0.2794 0.1778)
							(mid -0.249642 0.249642)
							(end -0.1778 0.2794)
						)
						(arc
							(start 0.1778 0.2794)
							(mid 0.249642 0.249642)
							(end 0.2794 0.1778)
						)
						(arc
							(start 0.2794 -0.1778)
							(mid 0.249642 -0.249642)
							(end 0.1778 -0.2794)
						)
					)
					(width 0)
					(fill yes)
				)
			)
		)
	)
	(footprint ""
		(layer "F.Cu")
		(at 64.11595 -144.08404 90)
		(property "Reference" "R181"
			(at 0 0 90)
			(layer "F.SilkS")
			(hide yes)
			(effects
				(font
					(size 1.27 1.27)
				)
			)
		)
		(property "Value" "2K2R2F-GP"
			(at 0.064008 -3.993896 90)
			(unlocked yes)
			(layer "F.Fab")
			(hide yes)
			(effects
				(font
					(size 1.016 1.016)
					(thickness 0.1524)
				)
			)
		)
		(property "Device Type" "R402H16"
			(at 0.064008 -5.517896 90)
			(unlocked yes)
			(layer "F.Fab")
			(hide yes)
			(effects
				(font
					(size 1.016 1.016)
					(thickness 0.1524)
				)
			)
		)
		(duplicate_pad_numbers_are_jumpers no)
		(fp_line
			(start 0.508 -0.9398)
			(end -0.508 -0.9398)
			(stroke
				(width 0.1524)
				(type default)
			)
			(layer "F.SilkS")
		)
		(fp_line
			(start -0.508 -0.9398)
			(end -0.508 0.9398)
			(stroke
				(width 0.1524)
				(type default)
			)
			(layer "F.SilkS")
		)
		(fp_rect
			(start -0.508 0.9398)
			(end 0.508 -0.9398)
			(stroke
				(width 0)
				(type default)
			)
			(fill no)
			(layer "F.CrtYd")
		)
		(fp_rect
			(start -0.508 0.9398)
			(end 0.508 -0.9398)
			(stroke
				(width 0)
				(type default)
			)
			(fill no)
			(layer "F.Fab")
		)
		(pad "1" smd custom
			(at 0 -0.4445 90)
			(size 0.1397 0.1397)
			(layers "F.Cu" "F.Mask" "F.Paste")
			(net "I2C_SCC_SCL_OUT")
			(options
				(clearance outline)
				(anchor circle)
			)
			(primitives
				(gr_poly
					(pts
						(arc
							(start -0.1778 -0.2794)
							(mid -0.249642 -0.249642)
							(end -0.2794 -0.1778)
						)
						(arc
							(start -0.2794 0.1778)
							(mid -0.249642 0.249642)
							(end -0.1778 0.2794)
						)
						(arc
							(start 0.1778 0.2794)
							(mid 0.249642 0.249642)
							(end 0.2794 0.1778)
						)
						(arc
							(start 0.2794 -0.1778)
							(mid 0.249642 -0.249642)
							(end 0.1778 -0.2794)
						)
					)
					(width 0)
					(fill yes)
				)
			)
		)
		(pad "2" smd custom
			(at 0 0.4445 90)
			(size 0.1397 0.1397)
			(layers "F.Cu" "F.Mask" "F.Paste")
			(net "P3V3_STBY")
			(options
				(clearance outline)
				(anchor circle)
			)
			(primitives
				(gr_poly
					(pts
						(arc
							(start -0.1778 -0.2794)
							(mid -0.249642 -0.249642)
							(end -0.2794 -0.1778)
						)
						(arc
							(start -0.2794 0.1778)
							(mid -0.249642 0.249642)
							(end -0.1778 0.2794)
						)
						(arc
							(start 0.1778 0.2794)
							(mid 0.249642 0.249642)
							(end 0.2794 0.1778)
						)
						(arc
							(start 0.2794 -0.1778)
							(mid 0.249642 -0.249642)
							(end 0.1778 -0.2794)
						)
					)
					(width 0)
					(fill yes)
				)
			)
		)
	)
	(footprint ""
		(layer "F.Cu")
		(at 90.59672 -149.190456 180)
		(property "Reference" "R24"
			(at 0 0 180)
			(layer "F.SilkS")
			(hide yes)
			(effects
				(font
					(size 1.27 1.27)
				)
			)
		)
		(property "Value" "10KR2F-2-GP"
			(at 0.064008 -3.993896 180)
			(unlocked yes)
			(layer "F.Fab")
			(hide yes)
			(effects
				(font
					(size 1.016 1.016)
					(thickness 0.1524)
				)
			)
		)
		(property "Device Type" "R402H16"
			(at 0.064008 -5.517896 180)
			(unlocked yes)
			(layer "F.Fab")
			(hide yes)
			(effects
				(font
					(size 1.016 1.016)
					(thickness 0.1524)
				)
			)
		)
		(duplicate_pad_numbers_are_jumpers no)
		(fp_line
			(start 0.508 -0.9398)
			(end -0.508 -0.9398)
			(stroke
				(width 0.1524)
				(type default)
			)
			(layer "F.SilkS")
		)
		(fp_line
			(start -0.508 -0.9398)
			(end -0.508 0.9398)
			(stroke
				(width 0.1524)
				(type default)
			)
			(layer "F.SilkS")
		)
		(fp_rect
			(start -0.508 0.9398)
			(end 0.508 -0.9398)
			(stroke
				(width 0)
				(type default)
			)
			(fill no)
			(layer "F.CrtYd")
		)
		(fp_rect
			(start -0.508 0.9398)
			(end 0.508 -0.9398)
			(stroke
				(width 0)
				(type default)
			)
			(fill no)
			(layer "F.Fab")
		)
		(pad "1" smd custom
			(at 0 -0.4445 180)
			(size 0.1397 0.1397)
			(layers "F.Cu" "F.Mask" "F.Paste")
			(net "P3V3_STBY")
			(options
				(clearance outline)
				(anchor circle)
			)
			(primitives
				(gr_poly
					(pts
						(arc
							(start -0.1778 -0.2794)
							(mid -0.249642 -0.249642)
							(end -0.2794 -0.1778)
						)
						(arc
							(start -0.2794 0.1778)
							(mid -0.249642 0.249642)
							(end -0.1778 0.2794)
						)
						(arc
							(start 0.1778 0.2794)
							(mid 0.249642 0.249642)
							(end 0.2794 0.1778)
						)
						(arc
							(start 0.2794 -0.1778)
							(mid 0.249642 -0.249642)
							(end 0.1778 -0.2794)
						)
					)
					(width 0)
					(fill yes)
				)
			)
		)
		(pad "2" smd custom
			(at 0 0.4445 180)
			(size 0.1397 0.1397)
			(layers "F.Cu" "F.Mask" "F.Paste")
			(net "USB_OCS_N1")
			(options
				(clearance outline)
				(anchor circle)
			)
			(primitives
				(gr_poly
					(pts
						(arc
							(start -0.1778 -0.2794)
							(mid -0.249642 -0.249642)
							(end -0.2794 -0.1778)
						)
						(arc
							(start -0.2794 0.1778)
							(mid -0.249642 0.249642)
							(end -0.1778 0.2794)
						)
						(arc
							(start 0.1778 0.2794)
							(mid 0.249642 0.249642)
							(end 0.2794 0.1778)
						)
						(arc
							(start 0.2794 -0.1778)
							(mid 0.249642 -0.249642)
							(end 0.1778 -0.2794)
						)
					)
					(width 0)
					(fill yes)
				)
			)
		)
	)
	(footprint ""
		(layer "F.Cu")
		(at 59.845956 -154.934412)
		(property "Reference" "TP50"
			(at 0 0 0)
			(layer "F.SilkS")
			(hide yes)
			(effects
				(font
					(size 1.27 1.27)
				)
			)
		)
		(property "Value" "TPAD28-2-GP"
			(at -0.0127 -1.6637 0)
			(unlocked yes)
			(layer "F.Fab")
			(hide yes)
			(effects
				(font
					(size 1.016 1.016)
					(thickness 0.1524)
				)
			)
		)
		(property "Device Type" "TPAD28"
			(at -0.0127 -3.1877 0)
			(unlocked yes)
			(layer "F.Fab")
			(hide yes)
			(effects
				(font
					(size 1.016 1.016)
					(thickness 0.1524)
				)
			)
		)
		(duplicate_pad_numbers_are_jumpers no)
		(fp_poly
			(pts
				(arc
					(start 0.3556 0)
					(mid -0.3556 0)
					(end 0.3556 0)
				)
			)
			(stroke
				(width 0)
				(type default)
			)
			(fill no)
			(layer "F.CrtYd")
		)
		(fp_poly
			(pts
				(arc
					(start 0.6096 0)
					(mid -0.6096 0)
					(end 0.6096 0)
				)
			)
			(stroke
				(width 0)
				(type default)
			)
			(fill no)
			(layer "F.Fab")
		)
		(pad "1" smd circle
			(at 0 0)
			(size 0.7112 0.7112)
			(layers "F.Cu" "F.Mask" "F.Paste")
			(net "TP_BMC_GPIOT0")
		)
	)
	(footprint ""
		(layer "F.Cu")
		(at 223.123506 -102.291642 180)
		(property "Reference" "C659"
			(at 0 0 180)
			(layer "F.SilkS")
			(hide yes)
			(effects
				(font
					(size 1.27 1.27)
				)
			)
		)
		(property "Value" "SCD1U16V2KX-3GP"
			(at 1.1811 -2.7051 180)
			(unlocked yes)
			(layer "F.Fab")
			(hide yes)
			(effects
				(font
					(size 1.016 1.016)
					(thickness 0.1524)
				)
			)
		)
		(property "Device Type" "C402H22"
			(at 1.1811 -4.2291 180)
			(unlocked yes)
			(layer "F.Fab")
			(hide yes)
			(effects
				(font
					(size 1.016 1.016)
					(thickness 0.1524)
				)
			)
		)
		(duplicate_pad_numbers_are_jumpers no)
		(fp_rect
			(start -0.4318 0.9525)
			(end 0.4318 -0.9525)
			(stroke
				(width 0)
				(type default)
			)
			(fill no)
			(layer "F.CrtYd")
		)
		(fp_rect
			(start -0.4318 0.9525)
			(end 0.4318 -0.9525)
			(stroke
				(width 0)
				(type default)
			)
			(fill no)
			(layer "F.Fab")
		)
		(pad "1" smd custom
			(at 0 -0.4445 180)
			(size 0.1524 0.1524)
			(layers "F.Cu" "F.Mask" "F.Paste")
			(net "P12V_STBY_VIN_U81")
			(options
				(clearance outline)
				(anchor circle)
			)
			(primitives
				(gr_poly
					(pts
						(arc
							(start 0.3048 -0.2032)
							(mid 0.275042 -0.275042)
							(end 0.2032 -0.3048)
						)
						(arc
							(start -0.2032 -0.3048)
							(mid -0.275042 -0.275042)
							(end -0.3048 -0.2032)
						)
						(arc
							(start -0.3048 0.2032)
							(mid -0.275042 0.275042)
							(end -0.2032 0.3048)
						)
						(arc
							(start 0.2032 0.3048)
							(mid 0.275042 0.275042)
							(end 0.3048 0.2032)
						)
					)
					(width 0)
					(fill yes)
				)
			)
		)
		(pad "2" smd custom
			(at 0 0.4445 180)
			(size 0.1524 0.1524)
			(layers "F.Cu" "F.Mask" "F.Paste")
			(net "GND")
			(options
				(clearance outline)
				(anchor circle)
			)
			(primitives
				(gr_poly
					(pts
						(arc
							(start 0.3048 -0.2032)
							(mid 0.275042 -0.275042)
							(end 0.2032 -0.3048)
						)
						(arc
							(start -0.2032 -0.3048)
							(mid -0.275042 -0.275042)
							(end -0.3048 -0.2032)
						)
						(arc
							(start -0.3048 0.2032)
							(mid -0.275042 0.275042)
							(end -0.2032 0.3048)
						)
						(arc
							(start 0.2032 0.3048)
							(mid 0.275042 0.275042)
							(end 0.3048 0.2032)
						)
					)
					(width 0)
					(fill yes)
				)
			)
		)
	)
)
